# BASEBOARD_FAB2 (Tioga Pass) — schematic netlist excerpt (pin names and nets, part order shuffled) for the footprints in the layout excerpt that follows; sources: Cadence DE-HDL packaged netlist, KiCad conversion of Wiwynn_Tioga_Pass_MB.brd

C6T1  CAP_A  0.01UF 25V 10% X7R  pkg 0402V  page 44 : A = M_A_VREF ; B = GND
C9P16  CAP_A  0.1UF 16V 10% EMPTY  pkg 0402V  page 200 : A = A_HSC_MOP ; B = AGND_HSC

Q2T1  NPN  MMBT3904 IC  pkg SM  page 157
  B  = H_CPU0_FAST_WAKE_B_N
  E  = GND
  C  = H_CPU0_FAST_WAKE

(kicad_pcb
	(version 20260206)
	(generator "pcbnew")
	(generator_version "10.0")
	(general
		(thickness 1.6)
		(legacy_teardrops no)
	)
	(paper "A4")
	(title_block
		(title "Wiwynn_Tioga_Pass_MB.brd")
		(comment 1 "Tioga Pass / footprints 3497-3499 of 4770")
	)
	(layers
		(0 "F.Cu" signal "TOP")
		(4 "In1.Cu" signal "L2GND")
		(6 "In2.Cu" signal "L3")
		(8 "In3.Cu" signal "L4GND")
		(10 "In4.Cu" signal "L5")
		(12 "In5.Cu" signal "L6GND")
		(14 "In6.Cu" signal "L7VCC")
		(16 "In7.Cu" signal "L8VCC")
		(18 "In8.Cu" signal "L9GND")
		(20 "In9.Cu" signal "L10")
		(22 "In10.Cu" signal "L11GND")
		(24 "In11.Cu" signal "L12")
		(26 "In12.Cu" signal "L13GND")
		(2 "B.Cu" signal "BOTTOM")
		(9 "F.Adhes" user "F.Adhesive")
		(11 "B.Adhes" user "B.Adhesive")
		(13 "F.Paste" user "Package Geometry/Pastemask Top")
		(15 "B.Paste" user "Package Geometry/Pastemask Bottom")
		(5 "F.SilkS" user "Ref Des/Silkscreen Top")
		(7 "B.SilkS" user "Ref Des/Silkscreen Bottom")
		(1 "F.Mask" user "Board Geometry/Soldermask Top")
		(3 "B.Mask" user "Board Geometry/Soldermask Bottom")
		(17 "Dwgs.User" user "User.Drawings")
		(19 "Cmts.User" user "User.Comments")
		(21 "Eco1.User" user "User.Eco1")
		(23 "Eco2.User" user "User.Eco2")
		(25 "Edge.Cuts" user "Board Geometry/Outline")
		(27 "Margin" user)
		(31 "F.CrtYd" user "Package Geometry/Place Bound Top")
		(29 "B.CrtYd" user "Package Geometry/Place Bound Bottom")
		(35 "F.Fab" user "Ref Des/Assembly Top")
		(33 "B.Fab" user "Ref Des/Assembly Bottom")
	)
	(footprint ""
		(layer "B.Cu")
		(at 195.453 -17.723612 90)
		(property "Reference" "C6T1"
			(at 0 0 90)
			(layer "B.SilkS")
			(hide yes)
			(effects
				(font
					(size 1.27 1.27)
				)
				(justify mirror)
			)
		)
		(property "Value" ""
			(at 0 0 90)
			(layer "B.Fab")
			(effects
				(font
					(size 1.27 1.27)
				)
				(justify mirror)
			)
		)
		(duplicate_pad_numbers_are_jumpers no)
		(fp_poly
			(pts
				(xy -0.3048 -0.1016) (xy -0.3048 0.9906) (xy 0.3048 0.9906) (xy 0.3048 -0.1016)
			)
			(stroke
				(width 0)
				(type default)
			)
			(fill no)
			(layer "B.CrtYd")
		)
		(fp_line
			(start 0.3048 -0.1016)
			(end 0.3048 0.9906)
			(stroke
				(width 0.1)
				(type default)
			)
			(layer "B.Fab")
		)
		(fp_line
			(start -0.3048 -0.1016)
			(end 0.3048 -0.1016)
			(stroke
				(width 0.1)
				(type default)
			)
			(layer "B.Fab")
		)
		(fp_line
			(start 0.3048 0.9906)
			(end -0.3048 0.9906)
			(stroke
				(width 0.1)
				(type default)
			)
			(layer "B.Fab")
		)
		(fp_line
			(start -0.3048 0.9906)
			(end -0.3048 -0.1016)
			(stroke
				(width 0.1)
				(type default)
			)
			(layer "B.Fab")
		)
		(pad "1" smd rect
			(at 0 0 270)
			(size 0.508 0.508)
			(layers "B.Cu" "B.Mask" "B.Paste")
			(net "M_A_VREF")
		)
		(pad "2" smd rect
			(at 0 0.889 270)
			(size 0.508 0.508)
			(layers "B.Cu" "B.Mask" "B.Paste")
			(net "GND")
		)
		(zone
			(layer "B.Cu")
			(hatch none 0.5)
			(connect_pads
				(clearance 0)
			)
			(min_thickness 0.25)
			(keepout
				(tracks allowed)
				(vias not_allowed)
				(pads allowed)
				(copperpour not_allowed)
				(footprints allowed)
			)
			(placement
				(enabled no)
				(sheetname "")
			)
			(fill
				(thermal_gap 0.5)
				(thermal_bridge_width 0.5)
				(island_removal_mode 0)
			)
			(polygon
				(pts
					(xy 195.707 -17.977612) (xy 195.707 -17.469612) (xy 196.088 -17.469612) (xy 196.088 -17.977612)
				)
			)
		)
		(zone
			(layer "B.Cu")
			(hatch none 0.5)
			(connect_pads
				(clearance 0)
			)
			(min_thickness 0.25)
			(keepout
				(tracks not_allowed)
				(vias allowed)
				(pads allowed)
				(copperpour not_allowed)
				(footprints allowed)
			)
			(placement
				(enabled no)
				(sheetname "")
			)
			(fill
				(thermal_gap 0.5)
				(thermal_bridge_width 0.5)
				(island_removal_mode 0)
			)
			(polygon
				(pts
					(xy 196.088 -17.977612) (xy 196.088 -17.469612) (xy 195.707 -17.469612) (xy 195.707 -17.977612)
				)
			)
		)
	)
	(footprint ""
		(layer "B.Cu")
		(at 418.8206 -11.587734 180)
		(property "Reference" "Q2T1"
			(at 1.22047 3.2004 90)
			(unlocked yes)
			(layer "B.SilkS")
			(effects
				(font
					(size 0.7874 0.5842)
					(thickness 0.1524)
				)
				(justify left mirror)
			)
		)
		(property "Value" ""
			(at 0 0 0)
			(layer "B.Fab")
			(effects
				(font
					(size 1.27 1.27)
				)
				(justify mirror)
			)
		)
		(duplicate_pad_numbers_are_jumpers no)
		(fp_line
			(start -0.381 0.635)
			(end -0.381 1.27)
			(stroke
				(width 0.1524)
				(type default)
			)
			(layer "B.SilkS")
		)
		(fp_line
			(start -0.9525 2.4765)
			(end -1.778 2.4765)
			(stroke
				(width 0.1524)
				(type default)
			)
			(layer "B.SilkS")
		)
		(fp_line
			(start -0.9525 -0.5715)
			(end -1.778 -0.5715)
			(stroke
				(width 0.1524)
				(type default)
			)
			(layer "B.SilkS")
		)
		(fp_line
			(start -1.778 2.4765)
			(end -1.778 1.5875)
			(stroke
				(width 0.1524)
				(type default)
			)
			(layer "B.SilkS")
		)
		(fp_line
			(start -1.778 -0.5715)
			(end -1.778 0.3175)
			(stroke
				(width 0.1524)
				(type default)
			)
			(layer "B.SilkS")
		)
		(fp_circle
			(center 0.9525 -0.9271)
			(end 0.8255 -0.9271)
			(stroke
				(width 0.254)
				(type default)
			)
			(fill no)
			(layer "B.SilkS")
		)
		(fp_poly
			(pts
				(xy -1.778 2.4765) (xy -0.381 2.4765) (xy -0.381 -0.5715) (xy -1.778 -0.5715)
			)
			(stroke
				(width 0)
				(type default)
			)
			(fill no)
			(layer "B.CrtYd")
		)
		(fp_line
			(start -0.381 2.4765)
			(end -1.778 2.4765)
			(stroke
				(width 0.1)
				(type default)
			)
			(layer "B.Fab")
		)
		(fp_line
			(start -0.381 -0.5715)
			(end -0.381 2.4765)
			(stroke
				(width 0.1)
				(type default)
			)
			(layer "B.Fab")
		)
		(fp_line
			(start -1.778 2.4765)
			(end -1.778 -0.5715)
			(stroke
				(width 0.1)
				(type default)
			)
			(layer "B.Fab")
		)
		(fp_line
			(start -1.778 -0.5715)
			(end -0.381 -0.5715)
			(stroke
				(width 0.1)
				(type default)
			)
			(layer "B.Fab")
		)
		(fp_circle
			(center 0.9525 -0.9271)
			(end 0.8255 -0.9271)
			(stroke
				(width 0.254)
				(type default)
			)
			(fill no)
			(layer "B.Fab")
		)
		(pad "1" smd rect
			(at 0 0)
			(size 1.143 0.508)
			(layers "B.Cu" "B.Mask" "B.Paste")
			(net "H_CPU0_FAST_WAKE_B_N")
		)
		(pad "2" smd rect
			(at 0 1.905)
			(size 1.143 0.508)
			(layers "B.Cu" "B.Mask" "B.Paste")
			(net "GND")
		)
		(pad "3" smd rect
			(at -2.159 0.9525)
			(size 1.143 0.508)
			(layers "B.Cu" "B.Mask" "B.Paste")
			(net "H_CPU0_FAST_WAKE")
		)
	)
	(footprint ""
		(layer "B.Cu")
		(at 18.415 -73.406 180)
		(property "Reference" "C9P16"
			(at 0 0 0)
			(layer "B.SilkS")
			(hide yes)
			(effects
				(font
					(size 1.27 1.27)
				)
				(justify mirror)
			)
		)
		(property "Value" ""
			(at 0 0 0)
			(layer "B.Fab")
			(effects
				(font
					(size 1.27 1.27)
				)
				(justify mirror)
			)
		)
		(duplicate_pad_numbers_are_jumpers no)
		(fp_rect
			(start -0.3048 0.9906)
			(end 0.3048 -0.1016)
			(stroke
				(width 0)
				(type default)
			)
			(fill no)
			(layer "B.CrtYd")
		)
		(fp_line
			(start 0.3048 0.9906)
			(end -0.3048 0.9906)
			(stroke
				(width 0.1)
				(type default)
			)
			(layer "B.Fab")
		)
		(fp_line
			(start 0.3048 -0.1016)
			(end 0.3048 0.9906)
			(stroke
				(width 0.1)
				(type default)
			)
			(layer "B.Fab")
		)
		(fp_line
			(start -0.3048 0.9906)
			(end -0.3048 -0.1016)
			(stroke
				(width 0.1)
				(type default)
			)
			(layer "B.Fab")
		)
		(fp_line
			(start -0.3048 -0.1016)
			(end 0.3048 -0.1016)
			(stroke
				(width 0.1)
				(type default)
			)
			(layer "B.Fab")
		)
		(pad "1" smd rect
			(at 0 0)
			(size 0.508 0.508)
			(layers "B.Cu" "B.Mask" "B.Paste")
			(net "A_HSC_MOP")
		)
		(pad "2" smd rect
			(at 0 0.889)
			(size 0.508 0.508)
			(layers "B.Cu" "B.Mask" "B.Paste")
			(net "AGND_HSC")
		)
		(zone
			(layer "B.Cu")
			(hatch none 0.5)
			(connect_pads
				(clearance 0)
			)
			(min_thickness 0.25)
			(keepout
				(tracks not_allowed)
				(vias allowed)
				(pads allowed)
				(copperpour not_allowed)
				(footprints allowed)
			)
			(placement
				(enabled no)
				(sheetname "")
			)
			(fill
				(thermal_gap 0.5)
				(thermal_bridge_width 0.5)
				(island_removal_mode 0)
			)
			(polygon
				(pts
					(xy 18.669 -74.041) (xy 18.161 -74.041) (xy 18.161 -73.66) (xy 18.669 -73.66)
				)
			)
		)
		(zone
			(layer "B.Cu")
			(hatch none 0.5)
			(connect_pads
				(clearance 0)
			)
			(min_thickness 0.25)
			(keepout
				(tracks allowed)
				(vias not_allowed)
				(pads allowed)
				(copperpour not_allowed)
				(footprints allowed)
			)
			(placement
				(enabled no)
				(sheetname "")
			)
			(fill
				(thermal_gap 0.5)
				(thermal_bridge_width 0.5)
				(island_removal_mode 0)
			)
			(polygon
				(pts
					(xy 18.669 -74.041) (xy 18.161 -74.041) (xy 18.161 -73.66) (xy 18.669 -73.66)
				)
			)
		)
	)
)
